(kicad_pcb
	(version 20260206)
	(generator "pcbnew")
	(generator_version "10.0")
	(general
		(thickness 1.6)
		(legacy_teardrops no)
	)
	(paper "A4")
	(title_block
		(title "peb — Lightning_PEB_BRD.brd")
		(comment 1 "Lightning (Wiwynn / Facebook NVMe JBOF) / footprints 1175-1181 of 2563")
	)
	(layers
		(0 "F.Cu" signal "TOP")
		(4 "In1.Cu" signal "L2GND")
		(6 "In2.Cu" signal "L3")
		(8 "In3.Cu" signal "L4VCC")
		(10 "In4.Cu" signal "L5VCC")
		(12 "In5.Cu" signal "L6")
		(14 "In6.Cu" signal "L7GND")
		(2 "B.Cu" signal "BOTTOM")
		(9 "F.Adhes" user "F.Adhesive")
		(11 "B.Adhes" user "B.Adhesive")
		(13 "F.Paste" user "Package Geometry/Pastemask Top")
		(15 "B.Paste" user "Package Geometry/Pastemask Bottom")
		(5 "F.SilkS" user "Ref Des/Silkscreen Top")
		(7 "B.SilkS" user "Ref Des/Silkscreen Bottom")
		(1 "F.Mask" user "Board Geometry/Soldermask Top")
		(3 "B.Mask" user "Board Geometry/Soldermask Bottom")
		(17 "Dwgs.User" user "User.Drawings")
		(19 "Cmts.User" user "User.Comments")
		(21 "Eco1.User" user "User.Eco1")
		(23 "Eco2.User" user "User.Eco2")
		(25 "Edge.Cuts" user "Board Geometry/Outline")
		(27 "Margin" user)
		(31 "F.CrtYd" user "Package Geometry/Place Bound Top")
		(29 "B.CrtYd" user "Package Geometry/Place Bound Bottom")
		(35 "F.Fab" user "Ref Des/Assembly Top")
		(33 "B.Fab" user "Ref Des/Assembly Bottom")
	)
	(footprint ""
		(layer "F.Cu")
		(at 87.9602 -80.899 -90)
		(property "Reference" "SR950"
			(at 0 0 270)
			(layer "F.SilkS")
			(hide yes)
			(effects
				(font
					(size 1.27 1.27)
				)
			)
		)
		(property "Value" "0R2J-2-GP"
			(at 0.064008 -3.993896 270)
			(unlocked yes)
			(layer "F.Fab")
			(hide yes)
			(effects
				(font
					(size 1.016 1.016)
					(thickness 0.1524)
				)
			)
		)
		(property "Device Type" "R402H16"
			(at 0.064008 -5.517896 270)
			(unlocked yes)
			(layer "F.Fab")
			(hide yes)
			(effects
				(font
					(size 1.016 1.016)
					(thickness 0.1524)
				)
			)
		)
		(duplicate_pad_numbers_are_jumpers no)
		(fp_line
			(start -0.508 -0.9398)
			(end -0.508 0.9398)
			(stroke
				(width 0.1524)
				(type default)
			)
			(layer "F.SilkS")
		)
		(fp_line
			(start 0.508 -0.9398)
			(end -0.508 -0.9398)
			(stroke
				(width 0.1524)
				(type default)
			)
			(layer "F.SilkS")
		)
		(fp_rect
			(start -0.508 0.9398)
			(end 0.508 -0.9398)
			(stroke
				(width 0)
				(type default)
			)
			(fill no)
			(layer "F.CrtYd")
		)
		(fp_rect
			(start -0.508 0.9398)
			(end 0.508 -0.9398)
			(stroke
				(width 0)
				(type default)
			)
			(fill no)
			(layer "F.Fab")
		)
		(pad "1" smd custom
			(at 0 -0.4445 270)
			(size 0.1397 0.1397)
			(layers "F.Cu" "F.Mask" "F.Paste")
			(net "SAS_SMART_R_TX")
			(options
				(clearance outline)
				(anchor circle)
			)
			(primitives
				(gr_poly
					(pts
						(arc
							(start -0.1778 -0.2794)
							(mid -0.249642 -0.249642)
							(end -0.2794 -0.1778)
						)
						(arc
							(start -0.2794 0.1778)
							(mid -0.249642 0.249642)
							(end -0.1778 0.2794)
						)
						(arc
							(start 0.1778 0.2794)
							(mid 0.249642 0.249642)
							(end 0.2794 0.1778)
						)
						(arc
							(start 0.2794 -0.1778)
							(mid 0.249642 -0.249642)
							(end 0.1778 -0.2794)
						)
					)
					(width 0)
					(fill yes)
				)
			)
		)
		(pad "2" smd custom
			(at 0 0.4445 270)
			(size 0.1397 0.1397)
			(layers "F.Cu" "F.Mask" "F.Paste")
			(net "UART_USOUT")
			(options
				(clearance outline)
				(anchor circle)
			)
			(primitives
				(gr_poly
					(pts
						(arc
							(start -0.1778 -0.2794)
							(mid -0.249642 -0.249642)
							(end -0.2794 -0.1778)
						)
						(arc
							(start -0.2794 0.1778)
							(mid -0.249642 0.249642)
							(end -0.1778 0.2794)
						)
						(arc
							(start 0.1778 0.2794)
							(mid 0.249642 0.249642)
							(end 0.2794 0.1778)
						)
						(arc
							(start 0.2794 -0.1778)
							(mid 0.249642 -0.249642)
							(end 0.1778 -0.2794)
						)
					)
					(width 0)
					(fill yes)
				)
			)
		)
	)
	(footprint ""
		(layer "F.Cu")
		(at 350.05264 -46.431454)
		(property "Reference" "C3212"
			(at 0 0 0)
			(layer "F.SilkS")
			(hide yes)
			(effects
				(font
					(size 1.27 1.27)
				)
			)
		)
		(property "Value" "SCD1U25V2KX-2-GP"
			(at 1.1811 -2.7051 0)
			(unlocked yes)
			(layer "F.Fab")
			(hide yes)
			(effects
				(font
					(size 1.016 1.016)
					(thickness 0.1524)
				)
			)
		)
		(property "Device Type" "C402H22"
			(at 1.1811 -4.2291 0)
			(unlocked yes)
			(layer "F.Fab")
			(hide yes)
			(effects
				(font
					(size 1.016 1.016)
					(thickness 0.1524)
				)
			)
		)
		(duplicate_pad_numbers_are_jumpers no)
		(fp_rect
			(start -0.4318 0.9525)
			(end 0.4318 -0.9525)
			(stroke
				(width 0)
				(type default)
			)
			(fill no)
			(layer "F.CrtYd")
		)
		(fp_rect
			(start -0.4318 0.9525)
			(end 0.4318 -0.9525)
			(stroke
				(width 0)
				(type default)
			)
			(fill no)
			(layer "F.Fab")
		)
		(pad "1" smd custom
			(at 0 -0.4445)
			(size 0.1524 0.1524)
			(layers "F.Cu" "F.Mask" "F.Paste")
			(net "P3V3_STBY")
			(options
				(clearance outline)
				(anchor circle)
			)
			(primitives
				(gr_poly
					(pts
						(arc
							(start 0.3048 -0.2032)
							(mid 0.275042 -0.275042)
							(end 0.2032 -0.3048)
						)
						(arc
							(start -0.2032 -0.3048)
							(mid -0.275042 -0.275042)
							(end -0.3048 -0.2032)
						)
						(arc
							(start -0.3048 0.2032)
							(mid -0.275042 0.275042)
							(end -0.2032 0.3048)
						)
						(arc
							(start 0.2032 0.3048)
							(mid 0.275042 0.275042)
							(end 0.3048 0.2032)
						)
					)
					(width 0)
					(fill yes)
				)
			)
		)
		(pad "2" smd custom
			(at 0 0.4445)
			(size 0.1524 0.1524)
			(layers "F.Cu" "F.Mask" "F.Paste")
			(net "GND")
			(options
				(clearance outline)
				(anchor circle)
			)
			(primitives
				(gr_poly
					(pts
						(arc
							(start 0.3048 -0.2032)
							(mid 0.275042 -0.275042)
							(end 0.2032 -0.3048)
						)
						(arc
							(start -0.2032 -0.3048)
							(mid -0.275042 -0.275042)
							(end -0.3048 -0.2032)
						)
						(arc
							(start -0.3048 0.2032)
							(mid -0.275042 0.275042)
							(end -0.2032 0.3048)
						)
						(arc
							(start 0.2032 0.3048)
							(mid 0.275042 0.275042)
							(end 0.3048 0.2032)
						)
					)
					(width 0)
					(fill yes)
				)
			)
		)
	)
	(footprint ""
		(layer "F.Cu")
		(at 278.207978 -212.420454 180)
		(property "Reference" "C98"
			(at 0 0 180)
			(layer "F.SilkS")
			(hide yes)
			(effects
				(font
					(size 1.27 1.27)
				)
			)
		)
		(property "Value" "SCD22U10V2KX-1GP"
			(at 1.1811 -2.7051 180)
			(unlocked yes)
			(layer "F.Fab")
			(hide yes)
			(effects
				(font
					(size 1.016 1.016)
					(thickness 0.1524)
				)
			)
		)
		(property "Device Type" "C402H22"
			(at 1.1811 -4.2291 180)
			(unlocked yes)
			(layer "F.Fab")
			(hide yes)
			(effects
				(font
					(size 1.016 1.016)
					(thickness 0.1524)
				)
			)
		)
		(duplicate_pad_numbers_are_jumpers no)
		(fp_rect
			(start -0.4318 0.9525)
			(end 0.4318 -0.9525)
			(stroke
				(width 0)
				(type default)
			)
			(fill no)
			(layer "F.CrtYd")
		)
		(fp_rect
			(start -0.4318 0.9525)
			(end 0.4318 -0.9525)
			(stroke
				(width 0)
				(type default)
			)
			(fill no)
			(layer "F.Fab")
		)
		(pad "1" smd custom
			(at 0 -0.4445 180)
			(size 0.1524 0.1524)
			(layers "F.Cu" "F.Mask" "F.Paste")
			(net "PCIE_TX_CAP_N33")
			(options
				(clearance outline)
				(anchor circle)
			)
			(primitives
				(gr_poly
					(pts
						(arc
							(start 0.3048 -0.2032)
							(mid 0.275042 -0.275042)
							(end 0.2032 -0.3048)
						)
						(arc
							(start -0.2032 -0.3048)
							(mid -0.275042 -0.275042)
							(end -0.3048 -0.2032)
						)
						(arc
							(start -0.3048 0.2032)
							(mid -0.275042 0.275042)
							(end -0.2032 0.3048)
						)
						(arc
							(start 0.2032 0.3048)
							(mid 0.275042 0.275042)
							(end 0.3048 0.2032)
						)
					)
					(width 0)
					(fill yes)
				)
			)
		)
		(pad "2" smd custom
			(at 0 0.4445 180)
			(size 0.1524 0.1524)
			(layers "F.Cu" "F.Mask" "F.Paste")
			(net "PCIE_TX_N33")
			(options
				(clearance outline)
				(anchor circle)
			)
			(primitives
				(gr_poly
					(pts
						(arc
							(start 0.3048 -0.2032)
							(mid 0.275042 -0.275042)
							(end 0.2032 -0.3048)
						)
						(arc
							(start -0.2032 -0.3048)
							(mid -0.275042 -0.275042)
							(end -0.3048 -0.2032)
						)
						(arc
							(start -0.3048 0.2032)
							(mid -0.275042 0.275042)
							(end -0.2032 0.3048)
						)
						(arc
							(start 0.2032 0.3048)
							(mid 0.275042 0.275042)
							(end 0.3048 0.2032)
						)
					)
					(width 0)
					(fill yes)
				)
			)
		)
	)
	(footprint ""
		(layer "F.Cu")
		(at 123.19 -18.63852 90)
		(property "Reference" "SR708"
			(at 0 0 90)
			(layer "F.SilkS")
			(hide yes)
			(effects
				(font
					(size 1.27 1.27)
				)
			)
		)
		(property "Value" "150R2F-1-GP"
			(at 0.064008 -3.993896 90)
			(unlocked yes)
			(layer "F.Fab")
			(hide yes)
			(effects
				(font
					(size 1.016 1.016)
					(thickness 0.1524)
				)
			)
		)
		(property "Device Type" "R402H16"
			(at 0.064008 -5.517896 90)
			(unlocked yes)
			(layer "F.Fab")
			(hide yes)
			(effects
				(font
					(size 1.016 1.016)
					(thickness 0.1524)
				)
			)
		)
		(duplicate_pad_numbers_are_jumpers no)
		(fp_line
			(start 0.508 -0.9398)
			(end -0.508 -0.9398)
			(stroke
				(width 0.1524)
				(type default)
			)
			(layer "F.SilkS")
		)
		(fp_line
			(start -0.508 -0.9398)
			(end -0.508 0.9398)
			(stroke
				(width 0.1524)
				(type default)
			)
			(layer "F.SilkS")
		)
		(fp_rect
			(start -0.508 0.9398)
			(end 0.508 -0.9398)
			(stroke
				(width 0)
				(type default)
			)
			(fill no)
			(layer "F.CrtYd")
		)
		(fp_rect
			(start -0.508 0.9398)
			(end 0.508 -0.9398)
			(stroke
				(width 0)
				(type default)
			)
			(fill no)
			(layer "F.Fab")
		)
		(pad "1" smd custom
			(at 0 -0.4445 90)
			(size 0.1397 0.1397)
			(layers "F.Cu" "F.Mask" "F.Paste")
			(net "P3V3_STBY")
			(options
				(clearance outline)
				(anchor circle)
			)
			(primitives
				(gr_poly
					(pts
						(arc
							(start -0.1778 -0.2794)
							(mid -0.249642 -0.249642)
							(end -0.2794 -0.1778)
						)
						(arc
							(start -0.2794 0.1778)
							(mid -0.249642 0.249642)
							(end -0.1778 0.2794)
						)
						(arc
							(start 0.1778 0.2794)
							(mid 0.249642 0.249642)
							(end 0.2794 0.1778)
						)
						(arc
							(start 0.2794 -0.1778)
							(mid 0.249642 -0.249642)
							(end 0.1778 -0.2794)
						)
					)
					(width 0)
					(fill yes)
				)
			)
		)
		(pad "2" smd custom
			(at 0 0.4445 90)
			(size 0.1397 0.1397)
			(layers "F.Cu" "F.Mask" "F.Paste")
			(net "LED_R_1")
			(options
				(clearance outline)
				(anchor circle)
			)
			(primitives
				(gr_poly
					(pts
						(arc
							(start -0.1778 -0.2794)
							(mid -0.249642 -0.249642)
							(end -0.2794 -0.1778)
						)
						(arc
							(start -0.2794 0.1778)
							(mid -0.249642 0.249642)
							(end -0.1778 0.2794)
						)
						(arc
							(start 0.1778 0.2794)
							(mid 0.249642 0.249642)
							(end 0.2794 0.1778)
						)
						(arc
							(start 0.2794 -0.1778)
							(mid 0.249642 -0.249642)
							(end 0.1778 -0.2794)
						)
					)
					(width 0)
					(fill yes)
				)
			)
		)
	)
	(footprint ""
		(layer "F.Cu")
		(at 205.359 -20.9296 90)
		(property "Reference" "R583"
			(at 0 0 90)
			(layer "F.SilkS")
			(hide yes)
			(effects
				(font
					(size 1.27 1.27)
				)
			)
		)
		(property "Value" "4K7R2F-GP"
			(at 0.064008 -3.993896 90)
			(unlocked yes)
			(layer "F.Fab")
			(hide yes)
			(effects
				(font
					(size 1.016 1.016)
					(thickness 0.1524)
				)
			)
		)
		(property "Device Type" "R402H16"
			(at 0.064008 -5.517896 90)
			(unlocked yes)
			(layer "F.Fab")
			(hide yes)
			(effects
				(font
					(size 1.016 1.016)
					(thickness 0.1524)
				)
			)
		)
		(duplicate_pad_numbers_are_jumpers no)
		(fp_line
			(start 0.508 -0.9398)
			(end -0.508 -0.9398)
			(stroke
				(width 0.1524)
				(type default)
			)
			(layer "F.SilkS")
		)
		(fp_line
			(start -0.508 -0.9398)
			(end -0.508 0.9398)
			(stroke
				(width 0.1524)
				(type default)
			)
			(layer "F.SilkS")
		)
		(fp_rect
			(start -0.508 0.9398)
			(end 0.508 -0.9398)
			(stroke
				(width 0)
				(type default)
			)
			(fill no)
			(layer "F.CrtYd")
		)
		(fp_rect
			(start -0.508 0.9398)
			(end 0.508 -0.9398)
			(stroke
				(width 0)
				(type default)
			)
			(fill no)
			(layer "F.Fab")
		)
		(pad "1" smd custom
			(at 0 -0.4445 90)
			(size 0.1397 0.1397)
			(layers "F.Cu" "F.Mask" "F.Paste")
			(net "MINISAS_CN16_D_I2C_INT#")
			(options
				(clearance outline)
				(anchor circle)
			)
			(primitives
				(gr_poly
					(pts
						(arc
							(start -0.1778 -0.2794)
							(mid -0.249642 -0.249642)
							(end -0.2794 -0.1778)
						)
						(arc
							(start -0.2794 0.1778)
							(mid -0.249642 0.249642)
							(end -0.1778 0.2794)
						)
						(arc
							(start 0.1778 0.2794)
							(mid 0.249642 0.249642)
							(end 0.2794 0.1778)
						)
						(arc
							(start 0.2794 -0.1778)
							(mid 0.249642 -0.249642)
							(end 0.1778 -0.2794)
						)
					)
					(width 0)
					(fill yes)
				)
			)
		)
		(pad "2" smd custom
			(at 0 0.4445 90)
			(size 0.1397 0.1397)
			(layers "F.Cu" "F.Mask" "F.Paste")
			(net "P3V3_STBY")
			(options
				(clearance outline)
				(anchor circle)
			)
			(primitives
				(gr_poly
					(pts
						(arc
							(start -0.1778 -0.2794)
							(mid -0.249642 -0.249642)
							(end -0.2794 -0.1778)
						)
						(arc
							(start -0.2794 0.1778)
							(mid -0.249642 0.249642)
							(end -0.1778 0.2794)
						)
						(arc
							(start 0.1778 0.2794)
							(mid 0.249642 0.249642)
							(end 0.2794 0.1778)
						)
						(arc
							(start 0.2794 -0.1778)
							(mid 0.249642 -0.249642)
							(end 0.1778 -0.2794)
						)
					)
					(width 0)
					(fill yes)
				)
			)
		)
	)
	(footprint ""
		(layer "F.Cu")
		(at 28.321 -116.713)
		(property "Reference" "R258"
			(at 0 0 0)
			(layer "F.SilkS")
			(hide yes)
			(effects
				(font
					(size 1.27 1.27)
				)
			)
		)
		(property "Value" "100KR2F-L1-GP"
			(at 0.064008 -3.993896 0)
			(unlocked yes)
			(layer "F.Fab")
			(hide yes)
			(effects
				(font
					(size 1.016 1.016)
					(thickness 0.1524)
				)
			)
		)
		(property "Device Type" "R402H16"
			(at 0.064008 -5.517896 0)
			(unlocked yes)
			(layer "F.Fab")
			(hide yes)
			(effects
				(font
					(size 1.016 1.016)
					(thickness 0.1524)
				)
			)
		)
		(duplicate_pad_numbers_are_jumpers no)
		(fp_line
			(start -0.508 -0.9398)
			(end -0.508 0.9398)
			(stroke
				(width 0.1524)
				(type default)
			)
			(layer "F.SilkS")
		)
		(fp_line
			(start 0.508 -0.9398)
			(end -0.508 -0.9398)
			(stroke
				(width 0.1524)
				(type default)
			)
			(layer "F.SilkS")
		)
		(fp_rect
			(start -0.508 0.9398)
			(end 0.508 -0.9398)
			(stroke
				(width 0)
				(type default)
			)
			(fill no)
			(layer "F.CrtYd")
		)
		(fp_rect
			(start -0.508 0.9398)
			(end 0.508 -0.9398)
			(stroke
				(width 0)
				(type default)
			)
			(fill no)
			(layer "F.Fab")
		)
		(pad "1" smd custom
			(at 0 -0.4445)
			(size 0.1397 0.1397)
			(layers "F.Cu" "F.Mask" "F.Paste")
			(net "TP_LPC_CPU_FRAME_N")
			(options
				(clearance outline)
				(anchor circle)
			)
			(primitives
				(gr_poly
					(pts
						(arc
							(start -0.1778 -0.2794)
							(mid -0.249642 -0.249642)
							(end -0.2794 -0.1778)
						)
						(arc
							(start -0.2794 0.1778)
							(mid -0.249642 0.249642)
							(end -0.1778 0.2794)
						)
						(arc
							(start 0.1778 0.2794)
							(mid 0.249642 0.249642)
							(end 0.2794 0.1778)
						)
						(arc
							(start 0.2794 -0.1778)
							(mid 0.249642 -0.249642)
							(end 0.1778 -0.2794)
						)
					)
					(width 0)
					(fill yes)
				)
			)
		)
		(pad "2" smd custom
			(at 0 0.4445)
			(size 0.1397 0.1397)
			(layers "F.Cu" "F.Mask" "F.Paste")
			(net "GND")
			(options
				(clearance outline)
				(anchor circle)
			)
			(primitives
				(gr_poly
					(pts
						(arc
							(start -0.1778 -0.2794)
							(mid -0.249642 -0.249642)
							(end -0.2794 -0.1778)
						)
						(arc
							(start -0.2794 0.1778)
							(mid -0.249642 0.249642)
							(end -0.1778 0.2794)
						)
						(arc
							(start 0.1778 0.2794)
							(mid 0.249642 0.249642)
							(end 0.2794 0.1778)
						)
						(arc
							(start 0.2794 -0.1778)
							(mid 0.249642 -0.249642)
							(end 0.1778 -0.2794)
						)
					)
					(width 0)
					(fill yes)
				)
			)
		)
	)
	(footprint ""
		(layer "F.Cu")
		(at 220.918024 -203.047092 180)
		(property "Reference" "R7979"
			(at 0 0 180)
			(layer "F.SilkS")
			(hide yes)
			(effects
				(font
					(size 1.27 1.27)
				)
			)
		)
		(property "Value" "0R2J-2-GP"
			(at 0.064008 -3.993896 180)
			(unlocked yes)
			(layer "F.Fab")
			(hide yes)
			(effects
				(font
					(size 1.016 1.016)
					(thickness 0.1524)
				)
			)
		)
		(property "Device Type" "R402H16"
			(at 0.064008 -5.517896 180)
			(unlocked yes)
			(layer "F.Fab")
			(hide yes)
			(effects
				(font
					(size 1.016 1.016)
					(thickness 0.1524)
				)
			)
		)
		(duplicate_pad_numbers_are_jumpers no)
		(fp_line
			(start 0.508 -0.9398)
			(end -0.508 -0.9398)
			(stroke
				(width 0.1524)
				(type default)
			)
			(layer "F.SilkS")
		)
		(fp_line
			(start -0.508 -0.9398)
			(end -0.508 0.9398)
			(stroke
				(width 0.1524)
				(type default)
			)
			(layer "F.SilkS")
		)
		(fp_rect
			(start -0.508 0.9398)
			(end 0.508 -0.9398)
			(stroke
				(width 0)
				(type default)
			)
			(fill no)
			(layer "F.CrtYd")
		)
		(fp_rect
			(start -0.508 0.9398)
			(end 0.508 -0.9398)
			(stroke
				(width 0)
				(type default)
			)
			(fill no)
			(layer "F.Fab")
		)
		(pad "1" smd custom
			(at 0 -0.4445 180)
			(size 0.1397 0.1397)
			(layers "F.Cu" "F.Mask" "F.Paste")
			(net "SSD_PERST#13")
			(options
				(clearance outline)
				(anchor circle)
			)
			(primitives
				(gr_poly
					(pts
						(arc
							(start -0.1778 -0.2794)
							(mid -0.249642 -0.249642)
							(end -0.2794 -0.1778)
						)
						(arc
							(start -0.2794 0.1778)
							(mid -0.249642 0.249642)
							(end -0.1778 0.2794)
						)
						(arc
							(start 0.1778 0.2794)
							(mid 0.249642 0.249642)
							(end 0.2794 0.1778)
						)
						(arc
							(start 0.2794 -0.1778)
							(mid 0.249642 -0.249642)
							(end 0.1778 -0.2794)
						)
					)
					(width 0)
					(fill yes)
				)
			)
		)
		(pad "2" smd custom
			(at 0 0.4445 180)
			(size 0.1397 0.1397)
			(layers "F.Cu" "F.Mask" "F.Paste")
			(net "SSD_PERST#13_R")
			(options
				(clearance outline)
				(anchor circle)
			)
			(primitives
				(gr_poly
					(pts
						(arc
							(start -0.1778 -0.2794)
							(mid -0.249642 -0.249642)
							(end -0.2794 -0.1778)
						)
						(arc
							(start -0.2794 0.1778)
							(mid -0.249642 0.249642)
							(end -0.1778 0.2794)
						)
						(arc
							(start 0.1778 0.2794)
							(mid 0.249642 0.249642)
							(end 0.2794 0.1778)
						)
						(arc
							(start 0.2794 -0.1778)
							(mid 0.249642 -0.249642)
							(end 0.1778 -0.2794)
						)
					)
					(width 0)
					(fill yes)
				)
			)
		)
	)
)
